(kicad_pcb
	(version 20260206)
	(generator "pcbnew")
	(generator_version "10.0")
	(general
		(thickness 1.6)
		(legacy_teardrops no)
	)
	(paper "A4")
	(title_block
		(title "01162023_DA0F0TEBIF0_F0T_Expander_BD_F_brd_V02_OCP.brd")
		(comment 1 "Grand Teton / footprints 3980-3986 of 9728")
	)
	(layers
		(0 "F.Cu" signal "TOP")
		(4 "In1.Cu" signal "GND")
		(6 "In2.Cu" signal "VCC")
		(8 "In3.Cu" signal "VCC1")
		(10 "In4.Cu" signal "GND1")
		(12 "In5.Cu" signal "IN1")
		(14 "In6.Cu" signal "GND2")
		(16 "In7.Cu" signal "IN2")
		(18 "In8.Cu" signal "GND3")
		(20 "In9.Cu" signal "IN3")
		(22 "In10.Cu" signal "GND4")
		(24 "In11.Cu" signal "IN4")
		(26 "In12.Cu" signal "GND5")
		(28 "In13.Cu" signal "IN5")
		(30 "In14.Cu" signal "GND6")
		(32 "In15.Cu" signal "IN6")
		(34 "In16.Cu" signal "GND7")
		(2 "B.Cu" signal "BOTTOM")
		(9 "F.Adhes" user "F.Adhesive")
		(11 "B.Adhes" user "B.Adhesive")
		(13 "F.Paste" user "Package Geometry/Pastemask Top")
		(15 "B.Paste" user "Package Geometry/Pastemask Bottom")
		(5 "F.SilkS" user "Ref Des/Silkscreen Top")
		(7 "B.SilkS" user "Ref Des/Silkscreen Bottom")
		(1 "F.Mask" user "Board Geometry/Soldermask Top")
		(3 "B.Mask" user "Board Geometry/Soldermask Bottom")
		(17 "Dwgs.User" user "User.Drawings")
		(19 "Cmts.User" user "User.Comments")
		(21 "Eco1.User" user "User.Eco1")
		(23 "Eco2.User" user "User.Eco2")
		(25 "Edge.Cuts" user "Board Geometry/Outline")
		(27 "Margin" user)
		(31 "F.CrtYd" user "Package Geometry/Place Bound Top")
		(29 "B.CrtYd" user "Package Geometry/Place Bound Bottom")
		(35 "F.Fab" user "Ref Des/Assembly Top")
		(33 "B.Fab" user "Ref Des/Assembly Bottom")
	)
	(footprint ""
		(layer "F.Cu")
		(at 249.992388 -31.825184 180)
		(property "Reference" "C490"
			(at 0 0 180)
			(layer "F.SilkS")
			(hide yes)
			(effects
				(font
					(size 1.27 1.27)
				)
			)
		)
		(property "Value" ""
			(at 0 0 180)
			(layer "F.Fab")
			(effects
				(font
					(size 1.27 1.27)
				)
			)
		)
		(duplicate_pad_numbers_are_jumpers no)
		(fp_line
			(start 0.299974 0.150114)
			(end -0.299974 0.150114)
			(stroke
				(width 0.1)
				(type default)
			)
			(layer "F.Fab")
		)
		(fp_line
			(start 0.299974 -0.150114)
			(end 0.299974 0.150114)
			(stroke
				(width 0.1)
				(type default)
			)
			(layer "F.Fab")
		)
		(fp_line
			(start -0.299974 0.150114)
			(end -0.299974 -0.150114)
			(stroke
				(width 0.1)
				(type default)
			)
			(layer "F.Fab")
		)
		(fp_line
			(start -0.299974 -0.150114)
			(end 0.299974 -0.150114)
			(stroke
				(width 0.1)
				(type default)
			)
			(layer "F.Fab")
		)
		(pad "1" smd rect
			(at -0.2667 0 180)
			(size 0.3048 0.381)
			(layers "F.Cu" "F.Mask" "F.Paste")
			(net "P5E_PEX2_STN2_TX_DN<46>")
		)
		(pad "2" smd rect
			(at 0.2667 0 180)
			(size 0.3048 0.381)
			(layers "F.Cu" "F.Mask" "F.Paste")
			(net "P5E_PEX2_STN2_TX_C_DN<46>")
		)
	)
	(footprint ""
		(layer "F.Cu")
		(at 69.62267 -22.867366 90)
		(property "Reference" "C3890"
			(at 0 0 90)
			(layer "F.SilkS")
			(hide yes)
			(effects
				(font
					(size 1.27 1.27)
				)
			)
		)
		(property "Value" ""
			(at 0 0 90)
			(layer "F.Fab")
			(effects
				(font
					(size 1.27 1.27)
				)
			)
		)
		(duplicate_pad_numbers_are_jumpers no)
		(fp_line
			(start 0.7874 -0.4064)
			(end 0.7874 0.4064)
			(stroke
				(width 0.1524)
				(type default)
			)
			(layer "F.SilkS")
		)
		(fp_line
			(start -0.7874 -0.4064)
			(end 0.7874 -0.4064)
			(stroke
				(width 0.1524)
				(type default)
			)
			(layer "F.SilkS")
		)
		(fp_line
			(start 0.7874 0.4064)
			(end -0.7874 0.4064)
			(stroke
				(width 0.1524)
				(type default)
			)
			(layer "F.SilkS")
		)
		(fp_line
			(start -0.7874 0.4064)
			(end -0.7874 -0.4064)
			(stroke
				(width 0.1524)
				(type default)
			)
			(layer "F.SilkS")
		)
		(fp_line
			(start -0.12065 -0.305054)
			(end -0.12065 -0.2794)
			(stroke
				(width 0.1)
				(type default)
			)
			(layer "F.Fab")
		)
		(fp_line
			(start -0.67945 -0.305054)
			(end -0.12065 -0.305054)
			(stroke
				(width 0.1)
				(type default)
			)
			(layer "F.Fab")
		)
		(fp_line
			(start 0.67945 -0.3048)
			(end 0.67945 0.3048)
			(stroke
				(width 0.1)
				(type default)
			)
			(layer "F.Fab")
		)
		(fp_line
			(start 0.12065 -0.3048)
			(end 0.67945 -0.3048)
			(stroke
				(width 0.1)
				(type default)
			)
			(layer "F.Fab")
		)
		(fp_line
			(start 0.12065 -0.2794)
			(end 0.12065 -0.3048)
			(stroke
				(width 0.1)
				(type default)
			)
			(layer "F.Fab")
		)
		(fp_line
			(start -0.12065 -0.2794)
			(end 0.12065 -0.2794)
			(stroke
				(width 0.1)
				(type default)
			)
			(layer "F.Fab")
		)
		(fp_line
			(start 0.120396 0.2794)
			(end -0.12065 0.2794)
			(stroke
				(width 0.1)
				(type default)
			)
			(layer "F.Fab")
		)
		(fp_line
			(start -0.12065 0.2794)
			(end -0.12065 0.3048)
			(stroke
				(width 0.1)
				(type default)
			)
			(layer "F.Fab")
		)
		(fp_line
			(start 0.67945 0.3048)
			(end 0.120396 0.3048)
			(stroke
				(width 0.1)
				(type default)
			)
			(layer "F.Fab")
		)
		(fp_line
			(start 0.120396 0.3048)
			(end 0.120396 0.2794)
			(stroke
				(width 0.1)
				(type default)
			)
			(layer "F.Fab")
		)
		(fp_line
			(start -0.12065 0.3048)
			(end -0.67945 0.3048)
			(stroke
				(width 0.1)
				(type default)
			)
			(layer "F.Fab")
		)
		(fp_line
			(start -0.67945 0.3048)
			(end -0.67945 -0.305054)
			(stroke
				(width 0.1)
				(type default)
			)
			(layer "F.Fab")
		)
		(pad "1" smd circle
			(at -0.40005 0 90)
			(size 0 0)
			(layers "F.Cu" "F.Mask" "F.Paste")
			(net "P12V_SSD2")
		)
		(pad "2" smd circle
			(at 0.40005 0 90)
			(size 0 0)
			(layers "F.Cu" "F.Mask" "F.Paste")
			(net "GND")
		)
	)
	(footprint ""
		(layer "F.Cu")
		(at 262.353298 -288.190432)
		(property "Reference" "L126"
			(at 0 0 0)
			(layer "F.SilkS")
			(hide yes)
			(effects
				(font
					(size 1.27 1.27)
				)
			)
		)
		(property "Value" ""
			(at 0 0 0)
			(layer "F.Fab")
			(effects
				(font
					(size 1.27 1.27)
				)
			)
		)
		(duplicate_pad_numbers_are_jumpers no)
		(fp_line
			(start -1.63576 -0.8128)
			(end -1.63576 0.8128)
			(stroke
				(width 0.1524)
				(type default)
			)
			(layer "F.SilkS")
		)
		(fp_line
			(start -1.63576 -0.8128)
			(end 1.63576 -0.8128)
			(stroke
				(width 0.1524)
				(type default)
			)
			(layer "F.SilkS")
		)
		(fp_line
			(start 1.63576 -0.8128)
			(end 1.63576 0.8128)
			(stroke
				(width 0.1524)
				(type default)
			)
			(layer "F.SilkS")
		)
		(fp_line
			(start 1.63576 0.8128)
			(end -1.63576 0.8128)
			(stroke
				(width 0.1524)
				(type default)
			)
			(layer "F.SilkS")
		)
		(fp_line
			(start -1.56083 -0.738632)
			(end -1.56083 0.7366)
			(stroke
				(width 0.1)
				(type default)
			)
			(layer "F.Fab")
		)
		(fp_line
			(start -1.56083 0.7366)
			(end -1.524 0.7366)
			(stroke
				(width 0.1)
				(type default)
			)
			(layer "F.Fab")
		)
		(fp_line
			(start -1.524 0.7366)
			(end 1.524 0.7366)
			(stroke
				(width 0.1)
				(type default)
			)
			(layer "F.Fab")
		)
		(fp_line
			(start 1.524 0.7366)
			(end 1.560576 0.7366)
			(stroke
				(width 0.1)
				(type default)
			)
			(layer "F.Fab")
		)
		(fp_line
			(start 1.560576 -0.738632)
			(end -1.56083 -0.738632)
			(stroke
				(width 0.1)
				(type default)
			)
			(layer "F.Fab")
		)
		(fp_line
			(start 1.560576 0.7366)
			(end 1.560576 -0.738632)
			(stroke
				(width 0.1)
				(type default)
			)
			(layer "F.Fab")
		)
		(pad "1" smd rect
			(at -0.94996 0 180)
			(size 1.1176 1.3716)
			(layers "F.Cu" "F.Mask" "F.Paste")
			(net "P1V8_PLL0_PEX2")
		)
		(pad "2" smd rect
			(at 0.94996 0 180)
			(size 1.1176 1.3716)
			(layers "F.Cu" "F.Mask" "F.Paste")
			(net "PCEPLL6_VDDA18_PEX2")
		)
	)
	(footprint ""
		(layer "F.Cu")
		(at 126.205488 -282.421584 -90)
		(property "Reference" "PC98"
			(at 0 0 270)
			(layer "F.SilkS")
			(hide yes)
			(effects
				(font
					(size 1.27 1.27)
				)
			)
		)
		(property "Value" ""
			(at 0 0 270)
			(layer "F.Fab")
			(effects
				(font
					(size 1.27 1.27)
				)
			)
		)
		(duplicate_pad_numbers_are_jumpers no)
		(fp_line
			(start -0.7874 0.4064)
			(end -0.7874 -0.4064)
			(stroke
				(width 0.1524)
				(type default)
			)
			(layer "F.SilkS")
		)
		(fp_line
			(start 0.7874 0.4064)
			(end -0.7874 0.4064)
			(stroke
				(width 0.1524)
				(type default)
			)
			(layer "F.SilkS")
		)
		(fp_line
			(start -0.7874 -0.4064)
			(end 0.7874 -0.4064)
			(stroke
				(width 0.1524)
				(type default)
			)
			(layer "F.SilkS")
		)
		(fp_line
			(start 0.7874 -0.4064)
			(end 0.7874 0.4064)
			(stroke
				(width 0.1524)
				(type default)
			)
			(layer "F.SilkS")
		)
		(fp_line
			(start -0.67945 0.3048)
			(end -0.67945 -0.305054)
			(stroke
				(width 0.1)
				(type default)
			)
			(layer "F.Fab")
		)
		(fp_line
			(start -0.12065 0.3048)
			(end -0.67945 0.3048)
			(stroke
				(width 0.1)
				(type default)
			)
			(layer "F.Fab")
		)
		(fp_line
			(start 0.120396 0.3048)
			(end 0.120396 0.2794)
			(stroke
				(width 0.1)
				(type default)
			)
			(layer "F.Fab")
		)
		(fp_line
			(start 0.67945 0.3048)
			(end 0.120396 0.3048)
			(stroke
				(width 0.1)
				(type default)
			)
			(layer "F.Fab")
		)
		(fp_line
			(start -0.12065 0.2794)
			(end -0.12065 0.3048)
			(stroke
				(width 0.1)
				(type default)
			)
			(layer "F.Fab")
		)
		(fp_line
			(start 0.120396 0.2794)
			(end -0.12065 0.2794)
			(stroke
				(width 0.1)
				(type default)
			)
			(layer "F.Fab")
		)
		(fp_line
			(start -0.12065 -0.2794)
			(end 0.12065 -0.2794)
			(stroke
				(width 0.1)
				(type default)
			)
			(layer "F.Fab")
		)
		(fp_line
			(start 0.12065 -0.2794)
			(end 0.12065 -0.3048)
			(stroke
				(width 0.1)
				(type default)
			)
			(layer "F.Fab")
		)
		(fp_line
			(start 0.12065 -0.3048)
			(end 0.67945 -0.3048)
			(stroke
				(width 0.1)
				(type default)
			)
			(layer "F.Fab")
		)
		(fp_line
			(start 0.67945 -0.3048)
			(end 0.67945 0.3048)
			(stroke
				(width 0.1)
				(type default)
			)
			(layer "F.Fab")
		)
		(fp_line
			(start -0.67945 -0.305054)
			(end -0.12065 -0.305054)
			(stroke
				(width 0.1)
				(type default)
			)
			(layer "F.Fab")
		)
		(fp_line
			(start -0.12065 -0.305054)
			(end -0.12065 -0.2794)
			(stroke
				(width 0.1)
				(type default)
			)
			(layer "F.Fab")
		)
		(pad "1" smd circle
			(at -0.40005 0 270)
			(size 0 0)
			(layers "F.Cu" "F.Mask" "F.Paste")
			(net "P0V8_PEX1_VCC1")
		)
		(pad "2" smd circle
			(at 0.40005 0 270)
			(size 0 0)
			(layers "F.Cu" "F.Mask" "F.Paste")
			(net "GND")
		)
	)
	(footprint ""
		(layer "F.Cu")
		(at 408.503882 -205.918308 -90)
		(property "Reference" "R6446"
			(at 0 0 270)
			(layer "F.SilkS")
			(hide yes)
			(effects
				(font
					(size 1.27 1.27)
				)
			)
		)
		(property "Value" ""
			(at 0 0 270)
			(layer "F.Fab")
			(effects
				(font
					(size 1.27 1.27)
				)
			)
		)
		(duplicate_pad_numbers_are_jumpers no)
		(fp_line
			(start -0.7874 0.4064)
			(end -0.7874 -0.4064)
			(stroke
				(width 0.1524)
				(type default)
			)
			(layer "F.SilkS")
		)
		(fp_line
			(start 0.7874 0.4064)
			(end -0.7874 0.4064)
			(stroke
				(width 0.1524)
				(type default)
			)
			(layer "F.SilkS")
		)
		(fp_line
			(start -0.7874 -0.4064)
			(end 0.7874 -0.4064)
			(stroke
				(width 0.1524)
				(type default)
			)
			(layer "F.SilkS")
		)
		(fp_line
			(start 0.7874 -0.4064)
			(end 0.7874 0.4064)
			(stroke
				(width 0.1524)
				(type default)
			)
			(layer "F.SilkS")
		)
		(fp_line
			(start -0.67945 0.3048)
			(end -0.67945 -0.305054)
			(stroke
				(width 0.1)
				(type default)
			)
			(layer "F.Fab")
		)
		(fp_line
			(start -0.12065 0.3048)
			(end -0.67945 0.3048)
			(stroke
				(width 0.1)
				(type default)
			)
			(layer "F.Fab")
		)
		(fp_line
			(start 0.120396 0.3048)
			(end 0.120396 0.2794)
			(stroke
				(width 0.1)
				(type default)
			)
			(layer "F.Fab")
		)
		(fp_line
			(start 0.67945 0.3048)
			(end 0.120396 0.3048)
			(stroke
				(width 0.1)
				(type default)
			)
			(layer "F.Fab")
		)
		(fp_line
			(start -0.12065 0.2794)
			(end -0.12065 0.3048)
			(stroke
				(width 0.1)
				(type default)
			)
			(layer "F.Fab")
		)
		(fp_line
			(start 0.120396 0.2794)
			(end -0.12065 0.2794)
			(stroke
				(width 0.1)
				(type default)
			)
			(layer "F.Fab")
		)
		(fp_line
			(start -0.12065 -0.2794)
			(end 0.12065 -0.2794)
			(stroke
				(width 0.1)
				(type default)
			)
			(layer "F.Fab")
		)
		(fp_line
			(start 0.12065 -0.2794)
			(end 0.12065 -0.3048)
			(stroke
				(width 0.1)
				(type default)
			)
			(layer "F.Fab")
		)
		(fp_line
			(start 0.12065 -0.3048)
			(end 0.67945 -0.3048)
			(stroke
				(width 0.1)
				(type default)
			)
			(layer "F.Fab")
		)
		(fp_line
			(start 0.67945 -0.3048)
			(end 0.67945 0.3048)
			(stroke
				(width 0.1)
				(type default)
			)
			(layer "F.Fab")
		)
		(fp_line
			(start -0.67945 -0.305054)
			(end -0.12065 -0.305054)
			(stroke
				(width 0.1)
				(type default)
			)
			(layer "F.Fab")
		)
		(fp_line
			(start -0.12065 -0.305054)
			(end -0.12065 -0.2794)
			(stroke
				(width 0.1)
				(type default)
			)
			(layer "F.Fab")
		)
		(pad "1" smd circle
			(at -0.40005 0 270)
			(size 0 0)
			(layers "F.Cu" "F.Mask" "F.Paste")
			(net "FPGA_PEX3_MODE_SEL1_ISO")
		)
		(pad "2" smd circle
			(at 0.40005 0 270)
			(size 0 0)
			(layers "F.Cu" "F.Mask" "F.Paste")
			(net "PEX3_MODE_SEL1")
		)
	)
	(footprint ""
		(layer "F.Cu")
		(at 25.524968 -350.098614 90)
		(property "Reference" "C185"
			(at 0 0 90)
			(layer "F.SilkS")
			(hide yes)
			(effects
				(font
					(size 1.27 1.27)
				)
			)
		)
		(property "Value" ""
			(at 0 0 90)
			(layer "F.Fab")
			(effects
				(font
					(size 1.27 1.27)
				)
			)
		)
		(duplicate_pad_numbers_are_jumpers no)
		(fp_line
			(start 0.299974 -0.150114)
			(end 0.299974 0.150114)
			(stroke
				(width 0.1)
				(type default)
			)
			(layer "F.Fab")
		)
		(fp_line
			(start -0.299974 -0.150114)
			(end 0.299974 -0.150114)
			(stroke
				(width 0.1)
				(type default)
			)
			(layer "F.Fab")
		)
		(fp_line
			(start 0.299974 0.150114)
			(end -0.299974 0.150114)
			(stroke
				(width 0.1)
				(type default)
			)
			(layer "F.Fab")
		)
		(fp_line
			(start -0.299974 0.150114)
			(end -0.299974 -0.150114)
			(stroke
				(width 0.1)
				(type default)
			)
			(layer "F.Fab")
		)
		(pad "1" smd rect
			(at -0.2667 0 90)
			(size 0.3048 0.381)
			(layers "F.Cu" "F.Mask" "F.Paste")
			(net "P5E_PEX0_STN7_TX_DP<115>")
		)
		(pad "2" smd rect
			(at 0.2667 0 90)
			(size 0.3048 0.381)
			(layers "F.Cu" "F.Mask" "F.Paste")
			(net "P5E_PEX0_STN7_TX_C_DP<115>")
		)
	)
	(footprint ""
		(layer "F.Cu")
		(at 379.59411 -34.248852)
		(property "Reference" "R5696"
			(at 0 0 0)
			(layer "F.SilkS")
			(hide yes)
			(effects
				(font
					(size 1.27 1.27)
				)
			)
		)
		(property "Value" ""
			(at 0 0 0)
			(layer "F.Fab")
			(effects
				(font
					(size 1.27 1.27)
				)
			)
		)
		(duplicate_pad_numbers_are_jumpers no)
		(fp_line
			(start -0.7874 -0.4064)
			(end 0.7874 -0.4064)
			(stroke
				(width 0.1524)
				(type default)
			)
			(layer "F.SilkS")
		)
		(fp_line
			(start -0.7874 0.4064)
			(end -0.7874 -0.4064)
			(stroke
				(width 0.1524)
				(type default)
			)
			(layer "F.SilkS")
		)
		(fp_line
			(start 0.7874 -0.4064)
			(end 0.7874 0.4064)
			(stroke
				(width 0.1524)
				(type default)
			)
			(layer "F.SilkS")
		)
		(fp_line
			(start 0.7874 0.4064)
			(end -0.7874 0.4064)
			(stroke
				(width 0.1524)
				(type default)
			)
			(layer "F.SilkS")
		)
		(fp_line
			(start -0.67945 -0.305054)
			(end -0.12065 -0.305054)
			(stroke
				(width 0.1)
				(type default)
			)
			(layer "F.Fab")
		)
		(fp_line
			(start -0.67945 0.3048)
			(end -0.67945 -0.305054)
			(stroke
				(width 0.1)
				(type default)
			)
			(layer "F.Fab")
		)
		(fp_line
			(start -0.12065 -0.305054)
			(end -0.12065 -0.2794)
			(stroke
				(width 0.1)
				(type default)
			)
			(layer "F.Fab")
		)
		(fp_line
			(start -0.12065 -0.2794)
			(end 0.12065 -0.2794)
			(stroke
				(width 0.1)
				(type default)
			)
			(layer "F.Fab")
		)
		(fp_line
			(start -0.12065 0.2794)
			(end -0.12065 0.3048)
			(stroke
				(width 0.1)
				(type default)
			)
			(layer "F.Fab")
		)
		(fp_line
			(start -0.12065 0.3048)
			(end -0.67945 0.3048)
			(stroke
				(width 0.1)
				(type default)
			)
			(layer "F.Fab")
		)
		(fp_line
			(start 0.120396 0.2794)
			(end -0.12065 0.2794)
			(stroke
				(width 0.1)
				(type default)
			)
			(layer "F.Fab")
		)
		(fp_line
			(start 0.120396 0.3048)
			(end 0.120396 0.2794)
			(stroke
				(width 0.1)
				(type default)
			)
			(layer "F.Fab")
		)
		(fp_line
			(start 0.12065 -0.3048)
			(end 0.67945 -0.3048)
			(stroke
				(width 0.1)
				(type default)
			)
			(layer "F.Fab")
		)
		(fp_line
			(start 0.12065 -0.2794)
			(end 0.12065 -0.3048)
			(stroke
				(width 0.1)
				(type default)
			)
			(layer "F.Fab")
		)
		(fp_line
			(start 0.67945 -0.3048)
			(end 0.67945 0.3048)
			(stroke
				(width 0.1)
				(type default)
			)
			(layer "F.Fab")
		)
		(fp_line
			(start 0.67945 0.3048)
			(end 0.120396 0.3048)
			(stroke
				(width 0.1)
				(type default)
			)
			(layer "F.Fab")
		)
		(pad "1" smd circle
			(at -0.40005 0)
			(size 0 0)
			(layers "F.Cu" "F.Mask" "F.Paste")
			(net "RST_SMB_SSD13_ISO_N")
		)
		(pad "2" smd circle
			(at 0.40005 0)
			(size 0 0)
			(layers "F.Cu" "F.Mask" "F.Paste")
			(net "P3V3_SSD13")
		)
	)
)
